(kicad_pcb
	(version 20260206)
	(generator "pcbnew")
	(generator_version "10.0")
	(general
		(thickness 1.6)
		(legacy_teardrops no)
	)
	(paper "A4")
	(title_block
		(title "pdpb — Lightning_PDPB_BRD.brd")
		(comment 1 "Lightning (Wiwynn / Facebook NVMe JBOF) / footprints 1081-1087 of 1140")
	)
	(layers
		(0 "F.Cu" signal "TOP")
		(4 "In1.Cu" signal "L2GND")
		(6 "In2.Cu" signal "L3")
		(8 "In3.Cu" signal "L4VCC")
		(10 "In4.Cu" signal "L5VCC")
		(12 "In5.Cu" signal "L6")
		(14 "In6.Cu" signal "L7GND")
		(2 "B.Cu" signal "BOTTOM")
		(9 "F.Adhes" user "F.Adhesive")
		(11 "B.Adhes" user "B.Adhesive")
		(13 "F.Paste" user "Package Geometry/Pastemask Top")
		(15 "B.Paste" user "Package Geometry/Pastemask Bottom")
		(5 "F.SilkS" user "Ref Des/Silkscreen Top")
		(7 "B.SilkS" user "Ref Des/Silkscreen Bottom")
		(1 "F.Mask" user "Board Geometry/Soldermask Top")
		(3 "B.Mask" user "Board Geometry/Soldermask Bottom")
		(17 "Dwgs.User" user "User.Drawings")
		(19 "Cmts.User" user "User.Comments")
		(21 "Eco1.User" user "User.Eco1")
		(23 "Eco2.User" user "User.Eco2")
		(25 "Edge.Cuts" user "Board Geometry/Outline")
		(27 "Margin" user)
		(31 "F.CrtYd" user "Package Geometry/Place Bound Top")
		(29 "B.CrtYd" user "Package Geometry/Place Bound Bottom")
		(35 "F.Fab" user "Ref Des/Assembly Top")
		(33 "B.Fab" user "Ref Des/Assembly Bottom")
	)
	(footprint ""
		(layer "F.Cu")
		(at 23.622 -256.667 180)
		(property "Reference" "R9904"
			(at 0 0 180)
			(layer "F.SilkS")
			(hide yes)
			(effects
				(font
					(size 1.27 1.27)
				)
			)
		)
		(property "Value" "1K82R2F-1-GP"
			(at 0.064008 -3.993896 180)
			(unlocked yes)
			(layer "F.Fab")
			(hide yes)
			(effects
				(font
					(size 1.016 1.016)
					(thickness 0.1524)
				)
			)
		)
		(property "Device Type" "R402H16"
			(at 0.064008 -5.517896 180)
			(unlocked yes)
			(layer "F.Fab")
			(hide yes)
			(effects
				(font
					(size 1.016 1.016)
					(thickness 0.1524)
				)
			)
		)
		(duplicate_pad_numbers_are_jumpers no)
		(fp_line
			(start 0.508 -0.9398)
			(end -0.508 -0.9398)
			(stroke
				(width 0.1524)
				(type default)
			)
			(layer "F.SilkS")
		)
		(fp_line
			(start -0.508 -0.9398)
			(end -0.508 0.9398)
			(stroke
				(width 0.1524)
				(type default)
			)
			(layer "F.SilkS")
		)
		(fp_rect
			(start -0.508 0.9398)
			(end 0.508 -0.9398)
			(stroke
				(width 0)
				(type default)
			)
			(fill no)
			(layer "F.CrtYd")
		)
		(fp_rect
			(start -0.508 0.9398)
			(end 0.508 -0.9398)
			(stroke
				(width 0)
				(type default)
			)
			(fill no)
			(layer "F.Fab")
		)
		(pad "1" smd custom
			(at 0 -0.4445 180)
			(size 0.1397 0.1397)
			(layers "F.Cu" "F.Mask" "F.Paste")
			(net "P12V")
			(options
				(clearance outline)
				(anchor circle)
			)
			(primitives
				(gr_poly
					(pts
						(arc
							(start -0.1778 -0.2794)
							(mid -0.249642 -0.249642)
							(end -0.2794 -0.1778)
						)
						(arc
							(start -0.2794 0.1778)
							(mid -0.249642 0.249642)
							(end -0.1778 0.2794)
						)
						(arc
							(start 0.1778 0.2794)
							(mid 0.249642 0.249642)
							(end 0.2794 0.1778)
						)
						(arc
							(start 0.2794 -0.1778)
							(mid 0.249642 -0.249642)
							(end 0.1778 -0.2794)
						)
					)
					(width 0)
					(fill yes)
				)
			)
		)
		(pad "2" smd custom
			(at 0 0.4445 180)
			(size 0.1397 0.1397)
			(layers "F.Cu" "F.Mask" "F.Paste")
			(net "DRV_ACT_12")
			(options
				(clearance outline)
				(anchor circle)
			)
			(primitives
				(gr_poly
					(pts
						(arc
							(start -0.1778 -0.2794)
							(mid -0.249642 -0.249642)
							(end -0.2794 -0.1778)
						)
						(arc
							(start -0.2794 0.1778)
							(mid -0.249642 0.249642)
							(end -0.1778 0.2794)
						)
						(arc
							(start 0.1778 0.2794)
							(mid 0.249642 0.249642)
							(end 0.2794 0.1778)
						)
						(arc
							(start 0.2794 -0.1778)
							(mid 0.249642 -0.249642)
							(end 0.1778 -0.2794)
						)
					)
					(width 0)
					(fill yes)
				)
			)
		)
	)
	(footprint ""
		(layer "F.Cu")
		(at 210.947 -197.9676 -90)
		(property "Reference" "Q42"
			(at 0 0 270)
			(layer "F.SilkS")
			(hide yes)
			(effects
				(font
					(size 1.27 1.27)
				)
			)
		)
		(property "Value" "2N7002A-7-GP"
			(at 0.127 -8.9662 270)
			(unlocked yes)
			(layer "F.Fab")
			(hide yes)
			(effects
				(font
					(size 1.016 1.016)
					(thickness 0.1524)
				)
			)
		)
		(property "Device Type" "SOT23DGS2D4H48"
			(at 0.127 -10.4902 270)
			(unlocked yes)
			(layer "F.Fab")
			(hide yes)
			(effects
				(font
					(size 1.016 1.016)
					(thickness 0.1524)
				)
			)
		)
		(duplicate_pad_numbers_are_jumpers no)
		(fp_line
			(start -1.651 1.778)
			(end 1.651 1.778)
			(stroke
				(width 0.1524)
				(type default)
			)
			(layer "F.SilkS")
		)
		(fp_line
			(start 1.651 1.778)
			(end 1.651 -1.778)
			(stroke
				(width 0.1524)
				(type default)
			)
			(layer "F.SilkS")
		)
		(fp_line
			(start -1.651 -1.778)
			(end -1.651 1.778)
			(stroke
				(width 0.1524)
				(type default)
			)
			(layer "F.SilkS")
		)
		(fp_line
			(start 1.651 -1.778)
			(end -1.651 -1.778)
			(stroke
				(width 0.1524)
				(type default)
			)
			(layer "F.SilkS")
		)
		(fp_poly
			(pts
				(xy -1.778 1.8796) (xy -1.778 -1.8796) (xy 1.778 -1.8796) (xy 1.778 1.8796)
			)
			(stroke
				(width 0)
				(type default)
			)
			(fill no)
			(layer "F.CrtYd")
		)
		(fp_poly
			(pts
				(xy -1.778 1.8796) (xy -1.778 -1.8796) (xy 1.778 -1.8796) (xy 1.778 1.8796)
			)
			(stroke
				(width 0)
				(type default)
			)
			(fill no)
			(layer "F.Fab")
		)
		(pad "D" smd custom
			(at 0 -0.9525 270)
			(size 0.1905 0.1905)
			(layers "F.Cu" "F.Mask" "F.Paste")
			(net "P12V_MOST3_GATE")
			(options
				(clearance outline)
				(anchor circle)
			)
			(primitives
				(gr_poly
					(pts
						(arc
							(start -0.1778 0.5715)
							(mid -0.321484 0.511984)
							(end -0.381 0.3683)
						)
						(arc
							(start -0.381 -0.3683)
							(mid -0.321484 -0.511984)
							(end -0.1778 -0.5715)
						)
						(arc
							(start 0.1778 -0.5715)
							(mid 0.321484 -0.511984)
							(end 0.381 -0.3683)
						)
						(arc
							(start 0.381 0.3683)
							(mid 0.321484 0.511984)
							(end 0.1778 0.5715)
						)
					)
					(width 0)
					(fill yes)
				)
			)
		)
		(pad "G" smd custom
			(at -0.98425 0.9525 270)
			(size 0.1905 0.1905)
			(layers "F.Cu" "F.Mask" "F.Paste")
			(net "SSD3_PWREN_R")
			(options
				(clearance outline)
				(anchor circle)
			)
			(primitives
				(gr_poly
					(pts
						(arc
							(start -0.1778 0.5715)
							(mid -0.321484 0.511984)
							(end -0.381 0.3683)
						)
						(arc
							(start -0.381 -0.3683)
							(mid -0.321484 -0.511984)
							(end -0.1778 -0.5715)
						)
						(arc
							(start 0.1778 -0.5715)
							(mid 0.321484 -0.511984)
							(end 0.381 -0.3683)
						)
						(arc
							(start 0.381 0.3683)
							(mid 0.321484 0.511984)
							(end 0.1778 0.5715)
						)
					)
					(width 0)
					(fill yes)
				)
			)
		)
		(pad "S" smd custom
			(at 0.98425 0.9525 270)
			(size 0.1905 0.1905)
			(layers "F.Cu" "F.Mask" "F.Paste")
			(net "GND")
			(options
				(clearance outline)
				(anchor circle)
			)
			(primitives
				(gr_poly
					(pts
						(arc
							(start -0.1778 0.5715)
							(mid -0.321484 0.511984)
							(end -0.381 0.3683)
						)
						(arc
							(start -0.381 -0.3683)
							(mid -0.321484 -0.511984)
							(end -0.1778 -0.5715)
						)
						(arc
							(start 0.1778 -0.5715)
							(mid 0.321484 -0.511984)
							(end 0.381 -0.3683)
						)
						(arc
							(start 0.381 0.3683)
							(mid 0.321484 0.511984)
							(end 0.1778 0.5715)
						)
					)
					(width 0)
					(fill yes)
				)
			)
		)
	)
	(footprint ""
		(layer "F.Cu")
		(at 97.663 -202.184)
		(property "Reference" "R9084"
			(at 0 0 0)
			(layer "F.SilkS")
			(hide yes)
			(effects
				(font
					(size 1.27 1.27)
				)
			)
		)
		(property "Value" "27R2F-GP"
			(at 0.064008 -3.993896 0)
			(unlocked yes)
			(layer "F.Fab")
			(hide yes)
			(effects
				(font
					(size 1.016 1.016)
					(thickness 0.1524)
				)
			)
		)
		(property "Device Type" "R402H16"
			(at 0.064008 -5.517896 0)
			(unlocked yes)
			(layer "F.Fab")
			(hide yes)
			(effects
				(font
					(size 1.016 1.016)
					(thickness 0.1524)
				)
			)
		)
		(duplicate_pad_numbers_are_jumpers no)
		(fp_line
			(start -0.508 -0.9398)
			(end -0.508 0.9398)
			(stroke
				(width 0.1524)
				(type default)
			)
			(layer "F.SilkS")
		)
		(fp_line
			(start 0.508 -0.9398)
			(end -0.508 -0.9398)
			(stroke
				(width 0.1524)
				(type default)
			)
			(layer "F.SilkS")
		)
		(fp_rect
			(start -0.508 0.9398)
			(end 0.508 -0.9398)
			(stroke
				(width 0)
				(type default)
			)
			(fill no)
			(layer "F.CrtYd")
		)
		(fp_rect
			(start -0.508 0.9398)
			(end 0.508 -0.9398)
			(stroke
				(width 0)
				(type default)
			)
			(fill no)
			(layer "F.Fab")
		)
		(pad "1" smd custom
			(at 0 -0.4445)
			(size 0.1397 0.1397)
			(layers "F.Cu" "F.Mask" "F.Paste")
			(net "PE_CLK_100M_DR4_1_R_P")
			(options
				(clearance outline)
				(anchor circle)
			)
			(primitives
				(gr_poly
					(pts
						(arc
							(start -0.1778 -0.2794)
							(mid -0.249642 -0.249642)
							(end -0.2794 -0.1778)
						)
						(arc
							(start -0.2794 0.1778)
							(mid -0.249642 0.249642)
							(end -0.1778 0.2794)
						)
						(arc
							(start 0.1778 0.2794)
							(mid 0.249642 0.249642)
							(end 0.2794 0.1778)
						)
						(arc
							(start 0.2794 -0.1778)
							(mid 0.249642 -0.249642)
							(end 0.1778 -0.2794)
						)
					)
					(width 0)
					(fill yes)
				)
			)
		)
		(pad "2" smd custom
			(at 0 0.4445)
			(size 0.1397 0.1397)
			(layers "F.Cu" "F.Mask" "F.Paste")
			(net "PE_CLK100M_DR4_1_P")
			(options
				(clearance outline)
				(anchor circle)
			)
			(primitives
				(gr_poly
					(pts
						(arc
							(start -0.1778 -0.2794)
							(mid -0.249642 -0.249642)
							(end -0.2794 -0.1778)
						)
						(arc
							(start -0.2794 0.1778)
							(mid -0.249642 0.249642)
							(end -0.1778 0.2794)
						)
						(arc
							(start 0.1778 0.2794)
							(mid 0.249642 0.249642)
							(end 0.2794 0.1778)
						)
						(arc
							(start 0.2794 -0.1778)
							(mid 0.249642 -0.249642)
							(end 0.1778 -0.2794)
						)
					)
					(width 0)
					(fill yes)
				)
			)
		)
	)
	(footprint ""
		(layer "F.Cu")
		(at 38.0746 -418.8714)
		(property "Reference" "R576"
			(at 0 0 0)
			(layer "F.SilkS")
			(hide yes)
			(effects
				(font
					(size 1.27 1.27)
				)
			)
		)
		(property "Value" "300KR2F-GP"
			(at 0.064008 -3.993896 0)
			(unlocked yes)
			(layer "F.Fab")
			(hide yes)
			(effects
				(font
					(size 1.016 1.016)
					(thickness 0.1524)
				)
			)
		)
		(property "Device Type" "R402H16"
			(at 0.064008 -5.517896 0)
			(unlocked yes)
			(layer "F.Fab")
			(hide yes)
			(effects
				(font
					(size 1.016 1.016)
					(thickness 0.1524)
				)
			)
		)
		(duplicate_pad_numbers_are_jumpers no)
		(fp_line
			(start -0.508 -0.9398)
			(end -0.508 0.9398)
			(stroke
				(width 0.1524)
				(type default)
			)
			(layer "F.SilkS")
		)
		(fp_line
			(start 0.508 -0.9398)
			(end -0.508 -0.9398)
			(stroke
				(width 0.1524)
				(type default)
			)
			(layer "F.SilkS")
		)
		(fp_rect
			(start -0.508 0.9398)
			(end 0.508 -0.9398)
			(stroke
				(width 0)
				(type default)
			)
			(fill no)
			(layer "F.CrtYd")
		)
		(fp_rect
			(start -0.508 0.9398)
			(end 0.508 -0.9398)
			(stroke
				(width 0)
				(type default)
			)
			(fill no)
			(layer "F.Fab")
		)
		(pad "1" smd custom
			(at 0 -0.4445)
			(size 0.1397 0.1397)
			(layers "F.Cu" "F.Mask" "F.Paste")
			(net "SW_SSD10_N")
			(options
				(clearance outline)
				(anchor circle)
			)
			(primitives
				(gr_poly
					(pts
						(arc
							(start -0.1778 -0.2794)
							(mid -0.249642 -0.249642)
							(end -0.2794 -0.1778)
						)
						(arc
							(start -0.2794 0.1778)
							(mid -0.249642 0.249642)
							(end -0.1778 0.2794)
						)
						(arc
							(start 0.1778 0.2794)
							(mid 0.249642 0.249642)
							(end 0.2794 0.1778)
						)
						(arc
							(start 0.2794 -0.1778)
							(mid 0.249642 -0.249642)
							(end 0.1778 -0.2794)
						)
					)
					(width 0)
					(fill yes)
				)
			)
		)
		(pad "2" smd custom
			(at 0 0.4445)
			(size 0.1397 0.1397)
			(layers "F.Cu" "F.Mask" "F.Paste")
			(net "P12V")
			(options
				(clearance outline)
				(anchor circle)
			)
			(primitives
				(gr_poly
					(pts
						(arc
							(start -0.1778 -0.2794)
							(mid -0.249642 -0.249642)
							(end -0.2794 -0.1778)
						)
						(arc
							(start -0.2794 0.1778)
							(mid -0.249642 0.249642)
							(end -0.1778 0.2794)
						)
						(arc
							(start 0.1778 0.2794)
							(mid 0.249642 0.249642)
							(end 0.2794 0.1778)
						)
						(arc
							(start 0.2794 -0.1778)
							(mid 0.249642 -0.249642)
							(end 0.1778 -0.2794)
						)
					)
					(width 0)
					(fill yes)
				)
			)
		)
	)
	(footprint ""
		(layer "F.Cu")
		(at 242.062 -422.529 90)
		(property "Reference" "PR9065"
			(at 0 0 90)
			(layer "F.SilkS")
			(hide yes)
			(effects
				(font
					(size 1.27 1.27)
				)
			)
		)
		(property "Value" "0R2J-2-GP"
			(at 0.064008 -3.993896 90)
			(unlocked yes)
			(layer "F.Fab")
			(hide yes)
			(effects
				(font
					(size 1.016 1.016)
					(thickness 0.1524)
				)
			)
		)
		(property "Device Type" "R402H16"
			(at 0.064008 -5.517896 90)
			(unlocked yes)
			(layer "F.Fab")
			(hide yes)
			(effects
				(font
					(size 1.016 1.016)
					(thickness 0.1524)
				)
			)
		)
		(duplicate_pad_numbers_are_jumpers no)
		(fp_line
			(start 0.508 -0.9398)
			(end -0.508 -0.9398)
			(stroke
				(width 0.1524)
				(type default)
			)
			(layer "F.SilkS")
		)
		(fp_line
			(start -0.508 -0.9398)
			(end -0.508 0.9398)
			(stroke
				(width 0.1524)
				(type default)
			)
			(layer "F.SilkS")
		)
		(fp_rect
			(start -0.508 0.9398)
			(end 0.508 -0.9398)
			(stroke
				(width 0)
				(type default)
			)
			(fill no)
			(layer "F.CrtYd")
		)
		(fp_rect
			(start -0.508 0.9398)
			(end 0.508 -0.9398)
			(stroke
				(width 0)
				(type default)
			)
			(fill no)
			(layer "F.Fab")
		)
		(pad "1" smd custom
			(at 0 -0.4445 90)
			(size 0.1397 0.1397)
			(layers "F.Cu" "F.Mask" "F.Paste")
			(net "SAS_I2C_C_BUF_SDA_R")
			(options
				(clearance outline)
				(anchor circle)
			)
			(primitives
				(gr_poly
					(pts
						(arc
							(start -0.1778 -0.2794)
							(mid -0.249642 -0.249642)
							(end -0.2794 -0.1778)
						)
						(arc
							(start -0.2794 0.1778)
							(mid -0.249642 0.249642)
							(end -0.1778 0.2794)
						)
						(arc
							(start 0.1778 0.2794)
							(mid 0.249642 0.249642)
							(end 0.2794 0.1778)
						)
						(arc
							(start 0.2794 -0.1778)
							(mid 0.249642 -0.249642)
							(end 0.1778 -0.2794)
						)
					)
					(width 0)
					(fill yes)
				)
			)
		)
		(pad "2" smd custom
			(at 0 0.4445 90)
			(size 0.1397 0.1397)
			(layers "F.Cu" "F.Mask" "F.Paste")
			(net "I2C_C_SDA")
			(options
				(clearance outline)
				(anchor circle)
			)
			(primitives
				(gr_poly
					(pts
						(arc
							(start -0.1778 -0.2794)
							(mid -0.249642 -0.249642)
							(end -0.2794 -0.1778)
						)
						(arc
							(start -0.2794 0.1778)
							(mid -0.249642 0.249642)
							(end -0.1778 0.2794)
						)
						(arc
							(start 0.1778 0.2794)
							(mid 0.249642 0.249642)
							(end 0.2794 0.1778)
						)
						(arc
							(start 0.2794 -0.1778)
							(mid 0.249642 -0.249642)
							(end 0.1778 -0.2794)
						)
					)
					(width 0)
					(fill yes)
				)
			)
		)
	)
	(footprint ""
		(layer "F.Cu")
		(at 19.4945 -370.0399)
		(property "Reference" "SR1144"
			(at 0 0 0)
			(layer "F.SilkS")
			(hide yes)
			(effects
				(font
					(size 1.27 1.27)
				)
			)
		)
		(property "Value" "4K7R2J-2-GP"
			(at 0.064008 -3.993896 0)
			(unlocked yes)
			(layer "F.Fab")
			(hide yes)
			(effects
				(font
					(size 1.016 1.016)
					(thickness 0.1524)
				)
			)
		)
		(property "Device Type" "R402H16"
			(at 0.064008 -5.517896 0)
			(unlocked yes)
			(layer "F.Fab")
			(hide yes)
			(effects
				(font
					(size 1.016 1.016)
					(thickness 0.1524)
				)
			)
		)
		(duplicate_pad_numbers_are_jumpers no)
		(fp_line
			(start -0.508 -0.9398)
			(end -0.508 0.9398)
			(stroke
				(width 0.1524)
				(type default)
			)
			(layer "F.SilkS")
		)
		(fp_line
			(start 0.508 -0.9398)
			(end -0.508 -0.9398)
			(stroke
				(width 0.1524)
				(type default)
			)
			(layer "F.SilkS")
		)
		(fp_rect
			(start -0.508 0.9398)
			(end 0.508 -0.9398)
			(stroke
				(width 0)
				(type default)
			)
			(fill no)
			(layer "F.CrtYd")
		)
		(fp_rect
			(start -0.508 0.9398)
			(end 0.508 -0.9398)
			(stroke
				(width 0)
				(type default)
			)
			(fill no)
			(layer "F.Fab")
		)
		(pad "1" smd custom
			(at 0 -0.4445)
			(size 0.1397 0.1397)
			(layers "F.Cu" "F.Mask" "F.Paste")
			(net "P3V3")
			(options
				(clearance outline)
				(anchor circle)
			)
			(primitives
				(gr_poly
					(pts
						(arc
							(start -0.1778 -0.2794)
							(mid -0.249642 -0.249642)
							(end -0.2794 -0.1778)
						)
						(arc
							(start -0.2794 0.1778)
							(mid -0.249642 0.249642)
							(end -0.1778 0.2794)
						)
						(arc
							(start 0.1778 0.2794)
							(mid 0.249642 0.249642)
							(end 0.2794 0.1778)
						)
						(arc
							(start 0.2794 -0.1778)
							(mid 0.249642 -0.249642)
							(end 0.1778 -0.2794)
						)
					)
					(width 0)
					(fill yes)
				)
			)
		)
		(pad "2" smd custom
			(at 0 0.4445)
			(size 0.1397 0.1397)
			(layers "F.Cu" "F.Mask" "F.Paste")
			(net "SSD_ACT_DR11")
			(options
				(clearance outline)
				(anchor circle)
			)
			(primitives
				(gr_poly
					(pts
						(arc
							(start -0.1778 -0.2794)
							(mid -0.249642 -0.249642)
							(end -0.2794 -0.1778)
						)
						(arc
							(start -0.2794 0.1778)
							(mid -0.249642 0.249642)
							(end -0.1778 0.2794)
						)
						(arc
							(start 0.1778 0.2794)
							(mid 0.249642 0.249642)
							(end 0.2794 0.1778)
						)
						(arc
							(start 0.2794 -0.1778)
							(mid 0.249642 -0.249642)
							(end 0.1778 -0.2794)
						)
					)
					(width 0)
					(fill yes)
				)
			)
		)
	)
	(footprint ""
		(layer "F.Cu")
		(at 38.851586 -343.484708 90)
		(property "Reference" "R9822"
			(at 0 0 90)
			(layer "F.SilkS")
			(hide yes)
			(effects
				(font
					(size 1.27 1.27)
				)
			)
		)
		(property "Value" "0R2J-2-GP"
			(at 0.064008 -3.993896 90)
			(unlocked yes)
			(layer "F.Fab")
			(hide yes)
			(effects
				(font
					(size 1.016 1.016)
					(thickness 0.1524)
				)
			)
		)
		(property "Device Type" "R402H16"
			(at 0.064008 -5.517896 90)
			(unlocked yes)
			(layer "F.Fab")
			(hide yes)
			(effects
				(font
					(size 1.016 1.016)
					(thickness 0.1524)
				)
			)
		)
		(duplicate_pad_numbers_are_jumpers no)
		(fp_line
			(start 0.508 -0.9398)
			(end -0.508 -0.9398)
			(stroke
				(width 0.1524)
				(type default)
			)
			(layer "F.SilkS")
		)
		(fp_line
			(start -0.508 -0.9398)
			(end -0.508 0.9398)
			(stroke
				(width 0.1524)
				(type default)
			)
			(layer "F.SilkS")
		)
		(fp_rect
			(start -0.508 0.9398)
			(end 0.508 -0.9398)
			(stroke
				(width 0)
				(type default)
			)
			(fill no)
			(layer "F.CrtYd")
		)
		(fp_rect
			(start -0.508 0.9398)
			(end 0.508 -0.9398)
			(stroke
				(width 0)
				(type default)
			)
			(fill no)
			(layer "F.Fab")
		)
		(pad "1" smd custom
			(at 0 -0.4445 90)
			(size 0.1397 0.1397)
			(layers "F.Cu" "F.Mask" "F.Paste")
			(net "ATTN_LED_DR6_R")
			(options
				(clearance outline)
				(anchor circle)
			)
			(primitives
				(gr_poly
					(pts
						(arc
							(start -0.1778 -0.2794)
							(mid -0.249642 -0.249642)
							(end -0.2794 -0.1778)
						)
						(arc
							(start -0.2794 0.1778)
							(mid -0.249642 0.249642)
							(end -0.1778 0.2794)
						)
						(arc
							(start 0.1778 0.2794)
							(mid 0.249642 0.249642)
							(end 0.2794 0.1778)
						)
						(arc
							(start 0.2794 -0.1778)
							(mid 0.249642 -0.249642)
							(end 0.1778 -0.2794)
						)
					)
					(width 0)
					(fill yes)
				)
			)
		)
		(pad "2" smd custom
			(at 0 0.4445 90)
			(size 0.1397 0.1397)
			(layers "F.Cu" "F.Mask" "F.Paste")
			(net "ATTN_LED_DR6_N")
			(options
				(clearance outline)
				(anchor circle)
			)
			(primitives
				(gr_poly
					(pts
						(arc
							(start -0.1778 -0.2794)
							(mid -0.249642 -0.249642)
							(end -0.2794 -0.1778)
						)
						(arc
							(start -0.2794 0.1778)
							(mid -0.249642 0.249642)
							(end -0.1778 0.2794)
						)
						(arc
							(start 0.1778 0.2794)
							(mid 0.249642 0.249642)
							(end 0.2794 0.1778)
						)
						(arc
							(start 0.2794 -0.1778)
							(mid 0.249642 -0.249642)
							(end 0.1778 -0.2794)
						)
					)
					(width 0)
					(fill yes)
				)
			)
		)
	)
)
